(kicad_pcb
	(version 20260206)
	(generator "pcbnew")
	(generator_version "10.0")
	(general
		(thickness 1.6)
		(legacy_teardrops no)
	)
	(paper "A4")
	(title_block
		(title "Bryce Canyon_Front Panel_16369-1_OCP.brd")
		(comment 1 "Bryce Canyon / footprints 42-49 of 154")
	)
	(layers
		(0 "F.Cu" signal "TOP")
		(4 "In1.Cu" signal "L2GND")
		(6 "In2.Cu" signal "L3VCC")
		(2 "B.Cu" signal "BOTTOM")
		(9 "F.Adhes" user "F.Adhesive")
		(11 "B.Adhes" user "B.Adhesive")
		(13 "F.Paste" user "Package Geometry/Pastemask Top")
		(15 "B.Paste" user "Package Geometry/Pastemask Bottom")
		(5 "F.SilkS" user "Ref Des/Silkscreen Top")
		(7 "B.SilkS" user "Ref Des/Silkscreen Bottom")
		(1 "F.Mask" user "Board Geometry/Soldermask Top")
		(3 "B.Mask" user "Board Geometry/Soldermask Bottom")
		(17 "Dwgs.User" user "User.Drawings")
		(19 "Cmts.User" user "User.Comments")
		(21 "Eco1.User" user "User.Eco1")
		(23 "Eco2.User" user "User.Eco2")
		(25 "Edge.Cuts" user "Board Geometry/Outline")
		(27 "Margin" user)
		(31 "F.CrtYd" user "Package Geometry/Place Bound Top")
		(29 "B.CrtYd" user "Package Geometry/Place Bound Bottom")
		(35 "F.Fab" user "Ref Des/Assembly Top")
		(33 "B.Fab" user "Ref Des/Assembly Bottom")
	)
	(footprint ""
		(layer "F.Cu")
		(at 53.02377 -29.8196 90)
		(property "Reference" "U6"
			(at 0 0 90)
			(layer "F.SilkS")
			(hide yes)
			(effects
				(font
					(size 1.27 1.27)
				)
			)
		)
		(property "Value" "TPS3422EGDRYR-GP"
			(at -0.1016 -5.4229 90)
			(unlocked yes)
			(layer "F.Fab")
			(hide yes)
			(effects
				(font
					(size 1.016 1.016)
					(thickness 0.1524)
				)
			)
		)
		(property "Device Type" "XSON6H24"
			(at -0.1016 -6.9469 90)
			(unlocked yes)
			(layer "F.Fab")
			(hide yes)
			(effects
				(font
					(size 1.016 1.016)
					(thickness 0.1524)
				)
			)
		)
		(duplicate_pad_numbers_are_jumpers no)
		(fp_line
			(start -0.7239 -0.762)
			(end -0.7239 -0.9398)
			(stroke
				(width 0.1524)
				(type default)
			)
			(layer "F.SilkS")
		)
		(fp_line
			(start -0.9779 -0.508)
			(end -0.7239 -0.762)
			(stroke
				(width 0.1524)
				(type default)
			)
			(layer "F.SilkS")
		)
		(fp_line
			(start -1.1557 -0.508)
			(end -0.9779 -0.508)
			(stroke
				(width 0.1524)
				(type default)
			)
			(layer "F.SilkS")
		)
		(fp_line
			(start 0.9779 0.508)
			(end 1.1557 0.508)
			(stroke
				(width 0.1524)
				(type default)
			)
			(layer "F.SilkS")
		)
		(fp_line
			(start -0.9779 0.508)
			(end -0.7239 0.762)
			(stroke
				(width 0.1524)
				(type default)
			)
			(layer "F.SilkS")
		)
		(fp_line
			(start -1.1557 0.508)
			(end -0.9779 0.508)
			(stroke
				(width 0.1524)
				(type default)
			)
			(layer "F.SilkS")
		)
		(fp_line
			(start 0.7239 0.762)
			(end 0.9779 0.508)
			(stroke
				(width 0.1524)
				(type default)
			)
			(layer "F.SilkS")
		)
		(fp_line
			(start -0.7239 0.762)
			(end -0.7239 0.9398)
			(stroke
				(width 0.1524)
				(type default)
			)
			(layer "F.SilkS")
		)
		(fp_line
			(start 0.7239 0.9398)
			(end 0.7239 0.762)
			(stroke
				(width 0.1524)
				(type default)
			)
			(layer "F.SilkS")
		)
		(fp_poly
			(pts
				(xy 0.846328 -0.607314) (xy 0.846328 -1.016) (xy 1.2319 -0.607314)
			)
			(stroke
				(width 0)
				(type default)
			)
			(fill yes)
			(layer "F.SilkS")
		)
		(fp_rect
			(start -0.7239 0.508)
			(end 0.7239 -0.508)
			(stroke
				(width 0)
				(type default)
			)
			(fill no)
			(layer "F.CrtYd")
		)
		(fp_poly
			(pts
				(xy -1.2319 1.016) (xy -1.2319 -1.016) (xy 1.2319 -1.016) (xy 1.2319 -0.0889) (xy 0.7239 -0.0889)
				(xy 0.7239 -0.508) (xy -0.7239 -0.508) (xy -0.7239 0.508) (xy 0.7239 0.508) (xy 0.7239 -0.0762)
				(xy 1.2319 -0.0762) (xy 1.2319 1.016)
			)
			(stroke
				(width 0)
				(type default)
			)
			(fill no)
			(layer "F.CrtYd")
		)
		(fp_rect
			(start -1.2319 1.016)
			(end 1.2319 -1.016)
			(stroke
				(width 0)
				(type default)
			)
			(fill no)
			(layer "F.Fab")
		)
		(pad "1" smd rect
			(at 0.50038 -0.310134 90)
			(size 0.3048 0.381)
			(layers "F.Cu" "F.Mask" "F.Paste")
			(net "SYS_RESET_BTN_B_N_R")
		)
		(pad "2" smd rect
			(at 0 -0.310134 90)
			(size 0.3048 0.381)
			(layers "F.Cu" "F.Mask" "F.Paste")
			(net "GND")
		)
		(pad "3" smd rect
			(at -0.50038 -0.310134 90)
			(size 0.3048 0.381)
			(layers "F.Cu" "F.Mask" "F.Paste")
			(net "SYS_RESET_BTN_B")
		)
		(pad "4" smd rect
			(at -0.50038 0.310134 90)
			(size 0.3048 0.381)
			(layers "F.Cu" "F.Mask" "F.Paste")
			(net "P3V3_STBY_B")
		)
		(pad "5" smd rect
			(at 0 0.310134 90)
			(size 0.3048 0.381)
			(layers "F.Cu" "F.Mask" "F.Paste")
			(net "RST_B_TS")
		)
		(pad "6" smd rect
			(at 0.50038 0.310134 90)
			(size 0.3048 0.381)
			(layers "F.Cu" "F.Mask" "F.Paste")
			(net "GND")
		)
	)
	(footprint ""
		(layer "F.Cu")
		(at 8.265668 -26.299668 90)
		(property "Reference" "C12"
			(at 0 0 90)
			(layer "F.SilkS")
			(hide yes)
			(effects
				(font
					(size 1.27 1.27)
				)
			)
		)
		(property "Value" "SCD1U16V2KX-3GP"
			(at 1.1811 -3.3909 90)
			(unlocked yes)
			(layer "F.Fab")
			(hide yes)
			(effects
				(font
					(size 2.54 2.54)
					(thickness 0.381)
				)
			)
		)
		(property "Device Type" "C402H22"
			(at 1.1811 -4.9149 90)
			(unlocked yes)
			(layer "F.Fab")
			(hide yes)
			(effects
				(font
					(size 2.54 2.54)
					(thickness 0.381)
				)
			)
		)
		(duplicate_pad_numbers_are_jumpers no)
		(fp_rect
			(start -0.4318 0.9525)
			(end 0.4318 -0.9525)
			(stroke
				(width 0)
				(type default)
			)
			(fill no)
			(layer "F.CrtYd")
		)
		(fp_rect
			(start -0.4318 0.9525)
			(end 0.4318 -0.9525)
			(stroke
				(width 0)
				(type default)
			)
			(fill no)
			(layer "F.Fab")
		)
		(pad "1" smd custom
			(at 0 -0.4445 90)
			(size 0.1524 0.1524)
			(layers "F.Cu" "F.Mask" "F.Paste")
			(net "P3V3_STBY_A")
			(options
				(clearance outline)
				(anchor circle)
			)
			(primitives
				(gr_poly
					(pts
						(arc
							(start 0.3048 -0.2032)
							(mid 0.275042 -0.275042)
							(end 0.2032 -0.3048)
						)
						(arc
							(start -0.2032 -0.3048)
							(mid -0.275042 -0.275042)
							(end -0.3048 -0.2032)
						)
						(arc
							(start -0.3048 0.2032)
							(mid -0.275042 0.275042)
							(end -0.2032 0.3048)
						)
						(arc
							(start 0.2032 0.3048)
							(mid 0.275042 0.275042)
							(end 0.3048 0.2032)
						)
					)
					(width 0)
					(fill yes)
				)
			)
		)
		(pad "2" smd custom
			(at 0 0.4445 90)
			(size 0.1524 0.1524)
			(layers "F.Cu" "F.Mask" "F.Paste")
			(net "GND")
			(options
				(clearance outline)
				(anchor circle)
			)
			(primitives
				(gr_poly
					(pts
						(arc
							(start 0.3048 -0.2032)
							(mid 0.275042 -0.275042)
							(end 0.2032 -0.3048)
						)
						(arc
							(start -0.2032 -0.3048)
							(mid -0.275042 -0.275042)
							(end -0.3048 -0.2032)
						)
						(arc
							(start -0.3048 0.2032)
							(mid -0.275042 0.275042)
							(end -0.2032 0.3048)
						)
						(arc
							(start 0.2032 0.3048)
							(mid 0.275042 0.275042)
							(end 0.3048 0.2032)
						)
					)
					(width 0)
					(fill yes)
				)
			)
		)
	)
	(footprint ""
		(layer "F.Cu")
		(at 45.355002 -50.041556 90)
		(property "Reference" "TP5"
			(at 0 0 90)
			(layer "F.SilkS")
			(hide yes)
			(effects
				(font
					(size 1.27 1.27)
				)
			)
		)
		(property "Value" "TPAD28-2-GP"
			(at -0.0127 -2.3495 90)
			(unlocked yes)
			(layer "F.Fab")
			(hide yes)
			(effects
				(font
					(size 2.54 2.54)
					(thickness 0.381)
				)
			)
		)
		(property "Device Type" "TPAD28"
			(at -0.0127 -3.8735 90)
			(unlocked yes)
			(layer "F.Fab")
			(hide yes)
			(effects
				(font
					(size 2.54 2.54)
					(thickness 0.381)
				)
			)
		)
		(duplicate_pad_numbers_are_jumpers no)
		(fp_poly
			(pts
				(arc
					(start 0 0.3556)
					(mid 0 -0.3556)
					(end 0 0.3556)
				)
			)
			(stroke
				(width 0)
				(type default)
			)
			(fill no)
			(layer "F.CrtYd")
		)
		(fp_poly
			(pts
				(arc
					(start 0 0.6096)
					(mid 0 -0.6096)
					(end 0 0.6096)
				)
			)
			(stroke
				(width 0)
				(type default)
			)
			(fill no)
			(layer "F.Fab")
		)
		(pad "1" smd circle
			(at 0 0 90)
			(size 0.7112 0.7112)
			(layers "F.Cu" "F.Mask" "F.Paste")
			(net "DEBUG_USB_B_DP")
		)
	)
	(footprint ""
		(layer "F.Cu")
		(at 10.1346 -20.9042 180)
		(property "Reference" "C19"
			(at 0 0 180)
			(layer "F.SilkS")
			(hide yes)
			(effects
				(font
					(size 1.27 1.27)
				)
			)
		)
		(property "Value" "SCD1U16V2KX-3GP"
			(at 1.1811 -2.7051 180)
			(unlocked yes)
			(layer "F.Fab")
			(hide yes)
			(effects
				(font
					(size 1.016 1.016)
					(thickness 0.1524)
				)
			)
		)
		(property "Device Type" "C402H22"
			(at 1.1811 -4.2291 180)
			(unlocked yes)
			(layer "F.Fab")
			(hide yes)
			(effects
				(font
					(size 1.016 1.016)
					(thickness 0.1524)
				)
			)
		)
		(duplicate_pad_numbers_are_jumpers no)
		(fp_rect
			(start -0.4318 0.9525)
			(end 0.4318 -0.9525)
			(stroke
				(width 0)
				(type default)
			)
			(fill no)
			(layer "F.CrtYd")
		)
		(fp_rect
			(start -0.4318 0.9525)
			(end 0.4318 -0.9525)
			(stroke
				(width 0)
				(type default)
			)
			(fill no)
			(layer "F.Fab")
		)
		(pad "1" smd custom
			(at 0 -0.4445 180)
			(size 0.1524 0.1524)
			(layers "F.Cu" "F.Mask" "F.Paste")
			(net "P3V3_STBY_A")
			(options
				(clearance outline)
				(anchor circle)
			)
			(primitives
				(gr_poly
					(pts
						(arc
							(start 0.3048 -0.2032)
							(mid 0.275042 -0.275042)
							(end 0.2032 -0.3048)
						)
						(arc
							(start -0.2032 -0.3048)
							(mid -0.275042 -0.275042)
							(end -0.3048 -0.2032)
						)
						(arc
							(start -0.3048 0.2032)
							(mid -0.275042 0.275042)
							(end -0.2032 0.3048)
						)
						(arc
							(start 0.2032 0.3048)
							(mid 0.275042 0.275042)
							(end 0.3048 0.2032)
						)
					)
					(width 0)
					(fill yes)
				)
			)
		)
		(pad "2" smd custom
			(at 0 0.4445 180)
			(size 0.1524 0.1524)
			(layers "F.Cu" "F.Mask" "F.Paste")
			(net "GND")
			(options
				(clearance outline)
				(anchor circle)
			)
			(primitives
				(gr_poly
					(pts
						(arc
							(start 0.3048 -0.2032)
							(mid 0.275042 -0.275042)
							(end 0.2032 -0.3048)
						)
						(arc
							(start -0.2032 -0.3048)
							(mid -0.275042 -0.275042)
							(end -0.3048 -0.2032)
						)
						(arc
							(start -0.3048 0.2032)
							(mid -0.275042 0.275042)
							(end -0.2032 0.3048)
						)
						(arc
							(start 0.2032 0.3048)
							(mid 0.275042 0.275042)
							(end 0.3048 0.2032)
						)
					)
					(width 0)
					(fill yes)
				)
			)
		)
	)
	(footprint ""
		(layer "F.Cu")
		(at 14.7066 -9.8044 -90)
		(property "Reference" "C22"
			(at 0 0 270)
			(layer "F.SilkS")
			(hide yes)
			(effects
				(font
					(size 1.27 1.27)
				)
			)
		)
		(property "Value" "SCD1U16V2KX-3GP"
			(at 1.1811 -2.7051 270)
			(unlocked yes)
			(layer "F.Fab")
			(hide yes)
			(effects
				(font
					(size 1.016 1.016)
					(thickness 0.1524)
				)
			)
		)
		(property "Device Type" "C402H22"
			(at 1.1811 -4.2291 270)
			(unlocked yes)
			(layer "F.Fab")
			(hide yes)
			(effects
				(font
					(size 1.016 1.016)
					(thickness 0.1524)
				)
			)
		)
		(duplicate_pad_numbers_are_jumpers no)
		(fp_rect
			(start -0.4318 0.9525)
			(end 0.4318 -0.9525)
			(stroke
				(width 0)
				(type default)
			)
			(fill no)
			(layer "F.CrtYd")
		)
		(fp_rect
			(start -0.4318 0.9525)
			(end 0.4318 -0.9525)
			(stroke
				(width 0)
				(type default)
			)
			(fill no)
			(layer "F.Fab")
		)
		(pad "1" smd custom
			(at 0 -0.4445 270)
			(size 0.1524 0.1524)
			(layers "F.Cu" "F.Mask" "F.Paste")
			(net "P3V3_STBY_A")
			(options
				(clearance outline)
				(anchor circle)
			)
			(primitives
				(gr_poly
					(pts
						(arc
							(start 0.3048 -0.2032)
							(mid 0.275042 -0.275042)
							(end 0.2032 -0.3048)
						)
						(arc
							(start -0.2032 -0.3048)
							(mid -0.275042 -0.275042)
							(end -0.3048 -0.2032)
						)
						(arc
							(start -0.3048 0.2032)
							(mid -0.275042 0.275042)
							(end -0.2032 0.3048)
						)
						(arc
							(start 0.2032 0.3048)
							(mid 0.275042 0.275042)
							(end 0.3048 0.2032)
						)
					)
					(width 0)
					(fill yes)
				)
			)
		)
		(pad "2" smd custom
			(at 0 0.4445 270)
			(size 0.1524 0.1524)
			(layers "F.Cu" "F.Mask" "F.Paste")
			(net "GND")
			(options
				(clearance outline)
				(anchor circle)
			)
			(primitives
				(gr_poly
					(pts
						(arc
							(start 0.3048 -0.2032)
							(mid 0.275042 -0.275042)
							(end 0.2032 -0.3048)
						)
						(arc
							(start -0.2032 -0.3048)
							(mid -0.275042 -0.275042)
							(end -0.3048 -0.2032)
						)
						(arc
							(start -0.3048 0.2032)
							(mid -0.275042 0.275042)
							(end -0.2032 0.3048)
						)
						(arc
							(start 0.2032 0.3048)
							(mid 0.275042 0.275042)
							(end 0.3048 0.2032)
						)
					)
					(width 0)
					(fill yes)
				)
			)
		)
	)
	(footprint ""
		(layer "F.Cu")
		(at 5.9182 -27.305 180)
		(property "Reference" "R47"
			(at 0 0 180)
			(layer "F.SilkS")
			(hide yes)
			(effects
				(font
					(size 1.27 1.27)
				)
			)
		)
		(property "Value" "100KR2F-L1-GP"
			(at 0.064008 -4.679696 180)
			(unlocked yes)
			(layer "F.Fab")
			(hide yes)
			(effects
				(font
					(size 2.54 2.54)
					(thickness 0.381)
				)
			)
		)
		(property "Device Type" "R402H16"
			(at 0.064008 -6.203696 180)
			(unlocked yes)
			(layer "F.Fab")
			(hide yes)
			(effects
				(font
					(size 2.54 2.54)
					(thickness 0.381)
				)
			)
		)
		(duplicate_pad_numbers_are_jumpers no)
		(fp_line
			(start 0.508 -0.9398)
			(end -0.508 -0.9398)
			(stroke
				(width 0.1524)
				(type default)
			)
			(layer "F.SilkS")
		)
		(fp_line
			(start -0.508 -0.9398)
			(end -0.508 0.9398)
			(stroke
				(width 0.1524)
				(type default)
			)
			(layer "F.SilkS")
		)
		(fp_rect
			(start -0.508 0.9398)
			(end 0.508 -0.9398)
			(stroke
				(width 0)
				(type default)
			)
			(fill no)
			(layer "F.CrtYd")
		)
		(fp_rect
			(start -0.508 0.9398)
			(end 0.508 -0.9398)
			(stroke
				(width 0)
				(type default)
			)
			(fill no)
			(layer "F.Fab")
		)
		(pad "1" smd custom
			(at 0 -0.4445 180)
			(size 0.1397 0.1397)
			(layers "F.Cu" "F.Mask" "F.Paste")
			(net "P3V3_STBY_A")
			(options
				(clearance outline)
				(anchor circle)
			)
			(primitives
				(gr_poly
					(pts
						(arc
							(start -0.1778 -0.2794)
							(mid -0.249642 -0.249642)
							(end -0.2794 -0.1778)
						)
						(arc
							(start -0.2794 0.1778)
							(mid -0.249642 0.249642)
							(end -0.1778 0.2794)
						)
						(arc
							(start 0.1778 0.2794)
							(mid 0.249642 0.249642)
							(end 0.2794 0.1778)
						)
						(arc
							(start 0.2794 -0.1778)
							(mid 0.249642 -0.249642)
							(end 0.1778 -0.2794)
						)
					)
					(width 0)
					(fill yes)
				)
			)
		)
		(pad "2" smd custom
			(at 0 0.4445 180)
			(size 0.1397 0.1397)
			(layers "F.Cu" "F.Mask" "F.Paste")
			(net "SYS_RESET_BTN_A")
			(options
				(clearance outline)
				(anchor circle)
			)
			(primitives
				(gr_poly
					(pts
						(arc
							(start -0.1778 -0.2794)
							(mid -0.249642 -0.249642)
							(end -0.2794 -0.1778)
						)
						(arc
							(start -0.2794 0.1778)
							(mid -0.249642 0.249642)
							(end -0.1778 0.2794)
						)
						(arc
							(start 0.1778 0.2794)
							(mid 0.249642 0.249642)
							(end 0.2794 0.1778)
						)
						(arc
							(start 0.2794 -0.1778)
							(mid 0.249642 -0.249642)
							(end 0.1778 -0.2794)
						)
					)
					(width 0)
					(fill yes)
				)
			)
		)
	)
	(footprint ""
		(layer "F.Cu")
		(at 43.8404 -12.3952 90)
		(property "Reference" "R60"
			(at 0 0 90)
			(layer "F.SilkS")
			(hide yes)
			(effects
				(font
					(size 1.27 1.27)
				)
			)
		)
		(property "Value" "100KR2F-L1-GP"
			(at 0.064008 -3.993896 90)
			(unlocked yes)
			(layer "F.Fab")
			(hide yes)
			(effects
				(font
					(size 1.016 1.016)
					(thickness 0.1524)
				)
			)
		)
		(property "Device Type" "R402H16"
			(at 0.064008 -5.517896 90)
			(unlocked yes)
			(layer "F.Fab")
			(hide yes)
			(effects
				(font
					(size 1.016 1.016)
					(thickness 0.1524)
				)
			)
		)
		(duplicate_pad_numbers_are_jumpers no)
		(fp_line
			(start 0.508 -0.9398)
			(end -0.508 -0.9398)
			(stroke
				(width 0.1524)
				(type default)
			)
			(layer "F.SilkS")
		)
		(fp_line
			(start -0.508 -0.9398)
			(end -0.508 0.9398)
			(stroke
				(width 0.1524)
				(type default)
			)
			(layer "F.SilkS")
		)
		(fp_rect
			(start -0.508 0.9398)
			(end 0.508 -0.9398)
			(stroke
				(width 0)
				(type default)
			)
			(fill no)
			(layer "F.CrtYd")
		)
		(fp_rect
			(start -0.508 0.9398)
			(end 0.508 -0.9398)
			(stroke
				(width 0)
				(type default)
			)
			(fill no)
			(layer "F.Fab")
		)
		(pad "1" smd custom
			(at 0 -0.4445 90)
			(size 0.1397 0.1397)
			(layers "F.Cu" "F.Mask" "F.Paste")
			(net "DEBUG_CARD_B_PRSNT")
			(options
				(clearance outline)
				(anchor circle)
			)
			(primitives
				(gr_poly
					(pts
						(arc
							(start -0.1778 -0.2794)
							(mid -0.249642 -0.249642)
							(end -0.2794 -0.1778)
						)
						(arc
							(start -0.2794 0.1778)
							(mid -0.249642 0.249642)
							(end -0.1778 0.2794)
						)
						(arc
							(start 0.1778 0.2794)
							(mid 0.249642 0.249642)
							(end 0.2794 0.1778)
						)
						(arc
							(start 0.2794 -0.1778)
							(mid 0.249642 -0.249642)
							(end 0.1778 -0.2794)
						)
					)
					(width 0)
					(fill yes)
				)
			)
		)
		(pad "2" smd custom
			(at 0 0.4445 90)
			(size 0.1397 0.1397)
			(layers "F.Cu" "F.Mask" "F.Paste")
			(net "GND")
			(options
				(clearance outline)
				(anchor circle)
			)
			(primitives
				(gr_poly
					(pts
						(arc
							(start -0.1778 -0.2794)
							(mid -0.249642 -0.249642)
							(end -0.2794 -0.1778)
						)
						(arc
							(start -0.2794 0.1778)
							(mid -0.249642 0.249642)
							(end -0.1778 0.2794)
						)
						(arc
							(start 0.1778 0.2794)
							(mid 0.249642 0.249642)
							(end 0.2794 0.1778)
						)
						(arc
							(start 0.2794 -0.1778)
							(mid 0.249642 -0.249642)
							(end 0.1778 -0.2794)
						)
					)
					(width 0)
					(fill yes)
				)
			)
		)
	)
	(footprint ""
		(layer "F.Cu")
		(at 2.437638 -63.583058 -90)
		(property "Reference" "C3"
			(at 0 0 270)
			(layer "F.SilkS")
			(hide yes)
			(effects
				(font
					(size 1.27 1.27)
				)
			)
		)
		(property "Value" "SC1U16V3KX-5GP"
			(at 0 -3.5052 270)
			(unlocked yes)
			(layer "F.Fab")
			(hide yes)
			(effects
				(font
					(size 2.54 2.54)
					(thickness 0.381)
				)
			)
		)
		(property "Device Type" "C603H36"
			(at 0 -5.0292 270)
			(unlocked yes)
			(layer "F.Fab")
			(hide yes)
			(effects
				(font
					(size 2.54 2.54)
					(thickness 0.381)
				)
			)
		)
		(duplicate_pad_numbers_are_jumpers no)
		(fp_line
			(start 0.508 0)
			(end -0.508 0)
			(stroke
				(width 0.2032)
				(type default)
			)
			(layer "F.SilkS")
		)
		(fp_rect
			(start -0.5842 1.3335)
			(end 0.5842 -1.3335)
			(stroke
				(width 0)
				(type default)
			)
			(fill no)
			(layer "F.CrtYd")
		)
		(fp_rect
			(start -0.5842 1.3335)
			(end 0.5842 -1.3335)
			(stroke
				(width 0)
				(type default)
			)
			(fill no)
			(layer "F.Fab")
		)
		(pad "1" smd custom
			(at 0 -0.762 270)
			(size 0.2159 0.2159)
			(layers "F.Cu" "F.Mask" "F.Paste")
			(net "P5V_USB_A")
			(options
				(clearance outline)
				(anchor circle)
			)
			(primitives
				(gr_poly
					(pts
						(arc
							(start -0.3302 -0.4318)
							(mid -0.402042 -0.402042)
							(end -0.4318 -0.3302)
						)
						(arc
							(start -0.4318 0.3302)
							(mid -0.402042 0.402042)
							(end -0.3302 0.4318)
						)
						(arc
							(start 0.3302 0.4318)
							(mid 0.402042 0.402042)
							(end 0.4318 0.3302)
						)
						(arc
							(start 0.4318 -0.3302)
							(mid 0.402042 -0.402042)
							(end 0.3302 -0.4318)
						)
					)
					(width 0)
					(fill yes)
				)
			)
		)
		(pad "2" smd custom
			(at 0 0.762 270)
			(size 0.2159 0.2159)
			(layers "F.Cu" "F.Mask" "F.Paste")
			(net "GND")
			(options
				(clearance outline)
				(anchor circle)
			)
			(primitives
				(gr_poly
					(pts
						(arc
							(start -0.3302 -0.4318)
							(mid -0.402042 -0.402042)
							(end -0.4318 -0.3302)
						)
						(arc
							(start -0.4318 0.3302)
							(mid -0.402042 0.402042)
							(end -0.3302 0.4318)
						)
						(arc
							(start 0.3302 0.4318)
							(mid 0.402042 0.402042)
							(end 0.4318 0.3302)
						)
						(arc
							(start 0.4318 -0.3302)
							(mid 0.402042 -0.402042)
							(end 0.3302 -0.4318)
						)
					)
					(width 0)
					(fill yes)
				)
			)
		)
	)
)
